(kicad_pcb
	(version 20260206)
	(generator "pcbnew")
	(generator_version "10.0")
	(general
		(thickness 1.6)
		(legacy_teardrops no)
	)
	(paper "A4")
	(title_block
		(title "01162023_DA0F0TEBIF0_F0T_Expander_BD_F_brd_V02_OCP.brd")
		(comment 1 "Grand Teton / footprints 9236-9239 of 9728")
	)
	(layers
		(0 "F.Cu" signal "TOP")
		(4 "In1.Cu" signal "GND")
		(6 "In2.Cu" signal "VCC")
		(8 "In3.Cu" signal "VCC1")
		(10 "In4.Cu" signal "GND1")
		(12 "In5.Cu" signal "IN1")
		(14 "In6.Cu" signal "GND2")
		(16 "In7.Cu" signal "IN2")
		(18 "In8.Cu" signal "GND3")
		(20 "In9.Cu" signal "IN3")
		(22 "In10.Cu" signal "GND4")
		(24 "In11.Cu" signal "IN4")
		(26 "In12.Cu" signal "GND5")
		(28 "In13.Cu" signal "IN5")
		(30 "In14.Cu" signal "GND6")
		(32 "In15.Cu" signal "IN6")
		(34 "In16.Cu" signal "GND7")
		(2 "B.Cu" signal "BOTTOM")
		(9 "F.Adhes" user "F.Adhesive")
		(11 "B.Adhes" user "B.Adhesive")
		(13 "F.Paste" user "Package Geometry/Pastemask Top")
		(15 "B.Paste" user "Package Geometry/Pastemask Bottom")
		(5 "F.SilkS" user "Ref Des/Silkscreen Top")
		(7 "B.SilkS" user "Ref Des/Silkscreen Bottom")
		(1 "F.Mask" user "Board Geometry/Soldermask Top")
		(3 "B.Mask" user "Board Geometry/Soldermask Bottom")
		(17 "Dwgs.User" user "User.Drawings")
		(19 "Cmts.User" user "User.Comments")
		(21 "Eco1.User" user "User.Eco1")
		(23 "Eco2.User" user "User.Eco2")
		(25 "Edge.Cuts" user "Board Geometry/Outline")
		(27 "Margin" user)
		(31 "F.CrtYd" user "Package Geometry/Place Bound Top")
		(29 "B.CrtYd" user "Package Geometry/Place Bound Bottom")
		(35 "F.Fab" user "Ref Des/Assembly Top")
		(33 "B.Fab" user "Ref Des/Assembly Bottom")
	)
	(footprint ""
		(layer "B.Cu")
		(at 99.35337 -333.067406 180)
		(property "Reference" "R1229"
			(at 0 0 0)
			(layer "B.SilkS")
			(hide yes)
			(effects
				(font
					(size 1.27 1.27)
				)
				(justify mirror)
			)
		)
		(property "Value" ""
			(at 0 0 0)
			(layer "B.Fab")
			(effects
				(font
					(size 1.27 1.27)
				)
				(justify mirror)
			)
		)
		(duplicate_pad_numbers_are_jumpers no)
		(fp_line
			(start 0.7874 0.4064)
			(end 0.7874 -0.4064)
			(stroke
				(width 0.1524)
				(type default)
			)
			(layer "B.SilkS")
		)
		(fp_line
			(start 0.7874 -0.4064)
			(end -0.7874 -0.4064)
			(stroke
				(width 0.1524)
				(type default)
			)
			(layer "B.SilkS")
		)
		(fp_line
			(start -0.7874 0.4064)
			(end 0.7874 0.4064)
			(stroke
				(width 0.1524)
				(type default)
			)
			(layer "B.SilkS")
		)
		(fp_line
			(start -0.7874 -0.4064)
			(end -0.7874 0.4064)
			(stroke
				(width 0.1524)
				(type default)
			)
			(layer "B.SilkS")
		)
		(fp_line
			(start 0.67945 0.3048)
			(end 0.67945 -0.305054)
			(stroke
				(width 0.1)
				(type default)
			)
			(layer "B.Fab")
		)
		(fp_line
			(start 0.67945 -0.305054)
			(end 0.12065 -0.305054)
			(stroke
				(width 0.1)
				(type default)
			)
			(layer "B.Fab")
		)
		(fp_line
			(start 0.12065 0.3048)
			(end 0.67945 0.3048)
			(stroke
				(width 0.1)
				(type default)
			)
			(layer "B.Fab")
		)
		(fp_line
			(start 0.12065 0.2794)
			(end 0.12065 0.3048)
			(stroke
				(width 0.1)
				(type default)
			)
			(layer "B.Fab")
		)
		(fp_line
			(start 0.12065 -0.2794)
			(end -0.12065 -0.2794)
			(stroke
				(width 0.1)
				(type default)
			)
			(layer "B.Fab")
		)
		(fp_line
			(start 0.12065 -0.305054)
			(end 0.12065 -0.2794)
			(stroke
				(width 0.1)
				(type default)
			)
			(layer "B.Fab")
		)
		(fp_line
			(start -0.120396 0.3048)
			(end -0.120396 0.2794)
			(stroke
				(width 0.1)
				(type default)
			)
			(layer "B.Fab")
		)
		(fp_line
			(start -0.120396 0.2794)
			(end 0.12065 0.2794)
			(stroke
				(width 0.1)
				(type default)
			)
			(layer "B.Fab")
		)
		(fp_line
			(start -0.12065 -0.2794)
			(end -0.12065 -0.3048)
			(stroke
				(width 0.1)
				(type default)
			)
			(layer "B.Fab")
		)
		(fp_line
			(start -0.12065 -0.3048)
			(end -0.67945 -0.3048)
			(stroke
				(width 0.1)
				(type default)
			)
			(layer "B.Fab")
		)
		(fp_line
			(start -0.67945 0.3048)
			(end -0.120396 0.3048)
			(stroke
				(width 0.1)
				(type default)
			)
			(layer "B.Fab")
		)
		(fp_line
			(start -0.67945 -0.3048)
			(end -0.67945 0.3048)
			(stroke
				(width 0.1)
				(type default)
			)
			(layer "B.Fab")
		)
		(pad "1" smd circle
			(at 0.40005 0)
			(size 0 0)
			(layers "B.Cu" "B.Mask" "B.Paste")
			(net "CLK_100M_DB800ZL_PEX2_S0_R_DP")
		)
		(pad "2" smd circle
			(at -0.40005 0)
			(size 0 0)
			(layers "B.Cu" "B.Mask" "B.Paste")
			(net "CLK_100M_DB800ZL_PEX2_S0_DP")
		)
	)
	(footprint ""
		(layer "B.Cu")
		(at 180.50002 -303.499774 -90)
		(property "Reference" "C3104"
			(at 0 0 90)
			(layer "B.SilkS")
			(hide yes)
			(effects
				(font
					(size 1.27 1.27)
				)
				(justify mirror)
			)
		)
		(property "Value" ""
			(at 0 0 90)
			(layer "B.Fab")
			(effects
				(font
					(size 1.27 1.27)
				)
				(justify mirror)
			)
		)
		(duplicate_pad_numbers_are_jumpers no)
		(fp_line
			(start -0.299974 0.150114)
			(end 0.299974 0.150114)
			(stroke
				(width 0.1)
				(type default)
			)
			(layer "B.Fab")
		)
		(fp_line
			(start 0.299974 0.150114)
			(end 0.299974 -0.150114)
			(stroke
				(width 0.1)
				(type default)
			)
			(layer "B.Fab")
		)
		(fp_line
			(start -0.299974 -0.150114)
			(end -0.299974 0.150114)
			(stroke
				(width 0.1)
				(type default)
			)
			(layer "B.Fab")
		)
		(fp_line
			(start 0.299974 -0.150114)
			(end -0.299974 -0.150114)
			(stroke
				(width 0.1)
				(type default)
			)
			(layer "B.Fab")
		)
		(pad "1" smd rect
			(at 0.2667 0 90)
			(size 0.3048 0.381)
			(layers "B.Cu" "B.Mask" "B.Paste")
			(net "P1V25_PEX1")
		)
		(pad "2" smd rect
			(at -0.2667 0 90)
			(size 0.3048 0.381)
			(layers "B.Cu" "B.Mask" "B.Paste")
			(net "GND")
		)
	)
	(footprint ""
		(layer "B.Cu")
		(at 238.890302 -366.750854 180)
		(property "Reference" "PR6607"
			(at 0 0 0)
			(layer "B.SilkS")
			(hide yes)
			(effects
				(font
					(size 1.27 1.27)
				)
				(justify mirror)
			)
		)
		(property "Value" ""
			(at 0 0 0)
			(layer "B.Fab")
			(effects
				(font
					(size 1.27 1.27)
				)
				(justify mirror)
			)
		)
		(duplicate_pad_numbers_are_jumpers no)
		(fp_line
			(start 0.7874 0.4064)
			(end 0.7874 -0.4064)
			(stroke
				(width 0.1524)
				(type default)
			)
			(layer "B.SilkS")
		)
		(fp_line
			(start 0.7874 -0.4064)
			(end -0.7874 -0.4064)
			(stroke
				(width 0.1524)
				(type default)
			)
			(layer "B.SilkS")
		)
		(fp_line
			(start -0.7874 0.4064)
			(end 0.7874 0.4064)
			(stroke
				(width 0.1524)
				(type default)
			)
			(layer "B.SilkS")
		)
		(fp_line
			(start -0.7874 -0.4064)
			(end -0.7874 0.4064)
			(stroke
				(width 0.1524)
				(type default)
			)
			(layer "B.SilkS")
		)
		(fp_line
			(start 0.67945 0.3048)
			(end 0.67945 -0.305054)
			(stroke
				(width 0.1)
				(type default)
			)
			(layer "B.Fab")
		)
		(fp_line
			(start 0.67945 -0.305054)
			(end 0.12065 -0.305054)
			(stroke
				(width 0.1)
				(type default)
			)
			(layer "B.Fab")
		)
		(fp_line
			(start 0.12065 0.3048)
			(end 0.67945 0.3048)
			(stroke
				(width 0.1)
				(type default)
			)
			(layer "B.Fab")
		)
		(fp_line
			(start 0.12065 0.2794)
			(end 0.12065 0.3048)
			(stroke
				(width 0.1)
				(type default)
			)
			(layer "B.Fab")
		)
		(fp_line
			(start 0.12065 -0.2794)
			(end -0.12065 -0.2794)
			(stroke
				(width 0.1)
				(type default)
			)
			(layer "B.Fab")
		)
		(fp_line
			(start 0.12065 -0.305054)
			(end 0.12065 -0.2794)
			(stroke
				(width 0.1)
				(type default)
			)
			(layer "B.Fab")
		)
		(fp_line
			(start -0.120396 0.3048)
			(end -0.120396 0.2794)
			(stroke
				(width 0.1)
				(type default)
			)
			(layer "B.Fab")
		)
		(fp_line
			(start -0.120396 0.2794)
			(end 0.12065 0.2794)
			(stroke
				(width 0.1)
				(type default)
			)
			(layer "B.Fab")
		)
		(fp_line
			(start -0.12065 -0.2794)
			(end -0.12065 -0.3048)
			(stroke
				(width 0.1)
				(type default)
			)
			(layer "B.Fab")
		)
		(fp_line
			(start -0.12065 -0.3048)
			(end -0.67945 -0.3048)
			(stroke
				(width 0.1)
				(type default)
			)
			(layer "B.Fab")
		)
		(fp_line
			(start -0.67945 0.3048)
			(end -0.120396 0.3048)
			(stroke
				(width 0.1)
				(type default)
			)
			(layer "B.Fab")
		)
		(fp_line
			(start -0.67945 -0.3048)
			(end -0.67945 0.3048)
			(stroke
				(width 0.1)
				(type default)
			)
			(layer "B.Fab")
		)
		(pad "1" smd circle
			(at 0.40005 0)
			(size 0 0)
			(layers "B.Cu" "B.Mask" "B.Paste")
			(net "P12V_HSC_GATE1")
		)
		(pad "2" smd circle
			(at -0.40005 0)
			(size 0 0)
			(layers "B.Cu" "B.Mask" "B.Paste")
			(net "HS_GATE1_R_1")
		)
	)
	(footprint ""
		(layer "B.Cu")
		(at 103.690674 -351.763584 -90)
		(property "Reference" "U424"
			(at 2.813304 4.248912 0)
			(unlocked yes)
			(layer "B.SilkS")
			(effects
				(font
					(size 0.7874 0.5842)
					(thickness 0.1524)
				)
				(justify mirror)
			)
		)
		(property "Value" ""
			(at 0 0 90)
			(layer "B.Fab")
			(effects
				(font
					(size 1.27 1.27)
				)
				(justify mirror)
			)
		)
		(duplicate_pad_numbers_are_jumpers no)
		(fp_line
			(start -2.500122 2.500122)
			(end -2.500122 2.01676)
			(stroke
				(width 0.1524)
				(type default)
			)
			(layer "B.SilkS")
		)
		(fp_line
			(start -2.01676 2.500122)
			(end -2.500122 2.500122)
			(stroke
				(width 0.1524)
				(type default)
			)
			(layer "B.SilkS")
		)
		(fp_line
			(start 2.500122 2.500122)
			(end 2.01676 2.500122)
			(stroke
				(width 0.1524)
				(type default)
			)
			(layer "B.SilkS")
		)
		(fp_line
			(start 2.500122 2.01676)
			(end 2.500122 2.500122)
			(stroke
				(width 0.1524)
				(type default)
			)
			(layer "B.SilkS")
		)
		(fp_line
			(start -2.500122 -2.01676)
			(end -2.500122 -2.500122)
			(stroke
				(width 0.1524)
				(type default)
			)
			(layer "B.SilkS")
		)
		(fp_line
			(start -2.500122 -2.500122)
			(end -2.01676 -2.500122)
			(stroke
				(width 0.1524)
				(type default)
			)
			(layer "B.SilkS")
		)
		(fp_line
			(start 2.01676 -2.500122)
			(end 2.500122 -2.500122)
			(stroke
				(width 0.1524)
				(type default)
			)
			(layer "B.SilkS")
		)
		(fp_line
			(start 2.500122 -2.500122)
			(end 2.500122 -2.01676)
			(stroke
				(width 0.1524)
				(type default)
			)
			(layer "B.SilkS")
		)
		(fp_poly
			(pts
				(xy 2.916936 -1.869948) (xy 3.514598 -3.065272) (xy 2.319274 -3.065272)
			)
			(stroke
				(width 0)
				(type default)
			)
			(fill yes)
			(layer "B.SilkS")
		)
		(fp_line
			(start -2.500122 2.500122)
			(end -2.500122 -2.500122)
			(stroke
				(width 0.1)
				(type default)
			)
			(layer "B.Fab")
		)
		(fp_line
			(start 2.500122 2.500122)
			(end -2.500122 2.500122)
			(stroke
				(width 0.1)
				(type default)
			)
			(layer "B.Fab")
		)
		(fp_line
			(start -2.500122 -2.500122)
			(end 2.500122 -2.500122)
			(stroke
				(width 0.1)
				(type default)
			)
			(layer "B.Fab")
		)
		(fp_line
			(start 2.500122 -2.500122)
			(end 2.500122 2.500122)
			(stroke
				(width 0.1)
				(type default)
			)
			(layer "B.Fab")
		)
		(fp_poly
			(pts
				(xy 3.044698 -1.75006) (xy 4.240022 -1.152398) (xy 4.240022 -2.347722)
			)
			(stroke
				(width 0)
				(type default)
			)
			(fill yes)
			(layer "B.Fab")
		)
		(pad "1" smd rect
			(at 2.3749 -1.75006 180)
			(size 0.254 0.5588)
			(layers "B.Cu" "B.Mask" "B.Paste")
			(net "FM_CLK_EN_R")
		)
		(pad "2" smd rect
			(at 2.3749 -1.249934 180)
			(size 0.254 0.5588)
			(layers "B.Cu" "B.Mask" "B.Paste")
			(net "P3V3_CLK_BUFFER_9ZXL0451E_S3_VZX3P3A")
		)
		(pad "3" smd rect
			(at 2.3749 -0.750062 180)
			(size 0.254 0.5588)
			(layers "B.Cu" "B.Mask" "B.Paste")
			(net "CLK_100M_MB_1_R_DP")
		)
		(pad "4" smd rect
			(at 2.3749 -0.249936 180)
			(size 0.254 0.5588)
			(layers "B.Cu" "B.Mask" "B.Paste")
			(net "CLK_100M_MB_1_R_DN")
		)
		(pad "5" smd rect
			(at 2.3749 0.249936 180)
			(size 0.254 0.5588)
			(layers "B.Cu" "B.Mask" "B.Paste")
			(net "SMB_9ZXL0451E_S3_ADDR0")
		)
		(pad "6" smd rect
			(at 2.3749 0.750062 180)
			(size 0.254 0.5588)
			(layers "B.Cu" "B.Mask" "B.Paste")
			(net "SMB_BMC_9FGL0451E_S3_SDA")
		)
		(pad "7" smd rect
			(at 2.3749 1.249934 180)
			(size 0.254 0.5588)
			(layers "B.Cu" "B.Mask" "B.Paste")
			(net "SMB_BMC_9FGL0451E_S3_SCL")
		)
		(pad "8" smd rect
			(at 2.3749 1.75006 180)
			(size 0.254 0.5588)
			(layers "B.Cu" "B.Mask" "B.Paste")
			(net "Net_9193")
		)
		(pad "9" smd rect
			(at 1.75006 2.3749 90)
			(size 0.254 0.5588)
			(layers "B.Cu" "B.Mask" "B.Paste")
			(net "Net_9194")
		)
		(pad "10" smd rect
			(at 1.249934 2.3749 90)
			(size 0.254 0.5588)
			(layers "B.Cu" "B.Mask" "B.Paste")
			(net "Net_9192")
		)
		(pad "11" smd rect
			(at 0.750062 2.3749 90)
			(size 0.254 0.5588)
			(layers "B.Cu" "B.Mask" "B.Paste")
			(net "Net_9191")
		)
		(pad "12" smd rect
			(at 0.249936 2.3749 90)
			(size 0.254 0.5588)
			(layers "B.Cu" "B.Mask" "B.Paste")
			(net "P3V3_CLK_BUFFER_9ZXL0451E_S3_VZX3P3")
		)
		(pad "13" smd rect
			(at -0.249936 2.3749 90)
			(size 0.254 0.5588)
			(layers "B.Cu" "B.Mask" "B.Paste")
			(net "CLK_100M_DB800ZL_PEX0_S3_DP")
		)
		(pad "14" smd rect
			(at -0.750062 2.3749 90)
			(size 0.254 0.5588)
			(layers "B.Cu" "B.Mask" "B.Paste")
			(net "CLK_100M_DB800ZL_PEX0_S3_DN")
		)
		(pad "15" smd rect
			(at -1.249934 2.3749 90)
			(size 0.254 0.5588)
			(layers "B.Cu" "B.Mask" "B.Paste")
			(net "PEX_S3_REF_CLK_BUFFER_EN_N")
		)
		(pad "16" smd rect
			(at -1.75006 2.3749 90)
			(size 0.254 0.5588)
			(layers "B.Cu" "B.Mask" "B.Paste")
			(net "P3V3_CLK_BUFFER_9ZXL0451E_S3_VZX3P3")
		)
		(pad "17" smd rect
			(at -2.3749 1.75006)
			(size 0.254 0.5588)
			(layers "B.Cu" "B.Mask" "B.Paste")
			(net "Net_9190")
		)
		(pad "18" smd rect
			(at -2.3749 1.249934)
			(size 0.254 0.5588)
			(layers "B.Cu" "B.Mask" "B.Paste")
			(net "PEX_S3_REF_CLK_BUFFER_EN_N")
		)
		(pad "19" smd rect
			(at -2.3749 0.750062)
			(size 0.254 0.5588)
			(layers "B.Cu" "B.Mask" "B.Paste")
			(net "CLK_100M_DB800ZL_PEX1_S3_DP")
		)
		(pad "20" smd rect
			(at -2.3749 0.249936)
			(size 0.254 0.5588)
			(layers "B.Cu" "B.Mask" "B.Paste")
			(net "CLK_100M_DB800ZL_PEX1_S3_DN")
		)
		(pad "21" smd rect
			(at -2.3749 -0.249936)
			(size 0.254 0.5588)
			(layers "B.Cu" "B.Mask" "B.Paste")
			(net "P3V3_CLK_BUFFER_9ZXL0451E_S3_VZX3P3")
		)
		(pad "22" smd rect
			(at -2.3749 -0.750062)
			(size 0.254 0.5588)
			(layers "B.Cu" "B.Mask" "B.Paste")
			(net "CLK_100M_DB800ZL_PEX2_S3_DP")
		)
		(pad "23" smd rect
			(at -2.3749 -1.249934)
			(size 0.254 0.5588)
			(layers "B.Cu" "B.Mask" "B.Paste")
			(net "CLK_100M_DB800ZL_PEX2_S3_DN")
		)
		(pad "24" smd rect
			(at -2.3749 -1.75006)
			(size 0.254 0.5588)
			(layers "B.Cu" "B.Mask" "B.Paste")
			(net "PEX_S3_REF_CLK_BUFFER_EN_N")
		)
		(pad "25" smd rect
			(at -1.75006 -2.3749 270)
			(size 0.254 0.5588)
			(layers "B.Cu" "B.Mask" "B.Paste")
			(net "P3V3_CLK_BUFFER_9ZXL0451E_S3_VZX3P3")
		)
		(pad "26" smd rect
			(at -1.249934 -2.3749 270)
			(size 0.254 0.5588)
			(layers "B.Cu" "B.Mask" "B.Paste")
			(net "PEX_S3_REF_CLK_BUFFER_EN_N")
		)
		(pad "27" smd rect
			(at -0.750062 -2.3749 270)
			(size 0.254 0.5588)
			(layers "B.Cu" "B.Mask" "B.Paste")
			(net "CLK_100M_DB800ZL_PEX3_S3_DP")
		)
		(pad "28" smd rect
			(at -0.249936 -2.3749 270)
			(size 0.254 0.5588)
			(layers "B.Cu" "B.Mask" "B.Paste")
			(net "CLK_100M_DB800ZL_PEX3_S3_DN")
		)
		(pad "29" smd rect
			(at 0.249936 -2.3749 270)
			(size 0.254 0.5588)
			(layers "B.Cu" "B.Mask" "B.Paste")
			(net "P3V3_CLK_BUFFER_9ZXL0451E_S3_VZX3P3")
		)
		(pad "30" smd rect
			(at 0.750062 -2.3749 270)
			(size 0.254 0.5588)
			(layers "B.Cu" "B.Mask" "B.Paste")
			(net "Net_9189")
		)
		(pad "31" smd rect
			(at 1.249934 -2.3749 270)
			(size 0.254 0.5588)
			(layers "B.Cu" "B.Mask" "B.Paste")
			(net "P3V3_CLK_BUFFER_9ZXL0451E_S3_VZX3P3A")
		)
		(pad "32" smd rect
			(at 1.75006 -2.3749 270)
			(size 0.254 0.5588)
			(layers "B.Cu" "B.Mask" "B.Paste")
			(net "PU_9ZXL0451E_S3_HBW")
		)
		(pad "33" smd rect
			(at 0 0 90)
			(size 3.1496 3.1496)
			(layers "B.Cu" "B.Mask" "B.Paste")
			(net "GND")
		)
		(zone
			(layer "B.Cu")
			(hatch none 0.5)
			(connect_pads
				(clearance 0)
			)
			(min_thickness 0.25)
			(keepout
				(tracks not_allowed)
				(vias allowed)
				(pads allowed)
				(copperpour not_allowed)
				(footprints allowed)
			)
			(placement
				(enabled no)
				(sheetname "")
			)
			(fill
				(thermal_gap 0.5)
				(thermal_bridge_width 0.5)
				(island_removal_mode 0)
			)
			(polygon
				(pts
					(xy 101.645974 -349.718884) (xy 104.915208 -349.718884) (xy 104.915208 -350.137984) (xy 102.065074 -350.137984)
					(xy 102.065074 -353.389184) (xy 105.316274 -353.389184) (xy 105.316274 -350.137984) (xy 104.940608 -350.137984)
					(xy 104.940608 -349.718884) (xy 105.735374 -349.718884) (xy 105.735374 -353.808284) (xy 101.645974 -353.808284)
				)
			)
		)
	)
)
